# Honey Badger  SEB_8Layer_Stackup.xlsx — Wiwynn (pcb-stackup)
|  |  |  |  |  |  | Version |  |  |  |  |  |  |  |  |  |  |  |  |  |  |
| Board Number: |  | 12004-SA |  |  |  | 01 |  |  |  |  |  |  |  |  |  |  |  |  |  |  |
| Project name: |  | Honey Badger |  |  |  |  |  |  |  |  |  |  |  |  |  |  |  |  |  |  |
| Model Name: |  | SAS EXPANDER BOARD |  |  |  |  |  |  |  |  |  |  |  |  |  |  |  |  |  |  |
| Layer Count: |  | 8 Layer |  |  |  |  |  |  |  |  |  |  |  |  |  |  |  |  |  |  |
| Date: |  | 41046 |  |  |  |  |  |  |  |  |  |  |  |  |  |  |  |  |  |  |
| Material: |  | TU722 +RTF |  |  |  |  |  |  |  | Single Ended Type(mil) |  |  |  |  | Differential Type(mil) |  |  |  |  |  |
| Green factor/Surface treatment/Tg: |  | Lead-Free/ OSP/Tg>170 |  |  |  |  |  |  | Imp | 50 |  |  |  | Imp | 100 |  |  |  |  |  |
| Customer: |  |  |  |  |  |  |  |  | Variation | Inner/Outer+/-5ohm |  |  |  | Variation | Inner/Outer+/-10% |  |  |  |  |  |
| EE engineer |  |  |  |  |  |  |  |  | Bus | Misc. |  |  |  | Bus | SAS/SATA |  |  |  |  |  |
| SI Engineer |  |  |  |  |  |  |  |  |  |  |  |  |  |  |  |  |  |  |  |  |
|  |  |  |  |  |  |  |  |  | Type | SE |  |  |  | Type | DP |  |  |  |  |  |
| Layer |  |  | Thickness |  | Glass/Copper Style | Er |  | Df(1G) | Layers | 1,3,6,8 |  |  |  | Layers | 1,3,6,8 |  |  |  |  |  |
|  |  | Cu oz | Wiwynn |  |  | Wiwynn |  |  |  | Wiwynn |  |  |  |  | Wiwynn |  |  |  |  |  |
|  | Mask |  | 0.5 |  |  | 3.8 |  |  |  | Width | Imp | Width | Imp |  | Width | Space | Imp | Width | Space | Imp |
| Top | Signal | 0.5 oz+plating | 1.9 |  |  |  |  |  | S1 | 4 |  |  |  | S1 | 4 | 9 |  |  |  |  |
|  | Prepreg |  | 2.7 |  |  | 3.5 |  |  |  |  |  |  |  |  |  |  |  |  |  |  |
| L2 | GND | 2 oz | 2.6 |  |  |  |  |  | P2 |  |  |  |  | P2 |  |  |  |  |  |  |
|  | Core |  | 4 |  |  | 3.7 |  |  |  |  |  |  |  |  |  |  |  |  |  |  |
| L3 | Signal | 1 oz | 1.3 |  |  |  |  |  | S3 | 4.5 |  |  |  | S3 |  |  |  |  |  |  |
|  | Prepreg |  | 12.5 |  |  | 4.4000000000000004 |  |  |  |  |  |  |  |  |  |  |  |  |  |  |
| L4 | PWR | 2 oz | 2.6 |  |  |  |  |  | P4 |  |  |  |  | P4 |  |  |  |  |  |  |
|  | Core |  | 4 |  |  | 4.0999999999999996 |  |  |  |  |  |  |  |  |  |  |  |  |  |  |
| L5 | PWR | 2 oz | 2.6 | 0 |  |  |  |  | S5 |  |  |  |  | S5 |  |  |  |  |  |  |
|  | Prepreg |  | 12.5 | 0 |  | 4.4000000000000004 | 0 |  |  |  |  |  |  |  |  |  |  |  |  |  |
| L6 | Signal | 1 oz | 1.3 | 0 |  |  |  |  | S6 | 4.5 |  |  |  | S6 |  |  |  |  |  |  |
|  | Core |  | 4 | 0 |  | 3.7 | 0 |  |  |  |  |  |  |  |  |  |  |  |  |  |
| L7 | GND | 2 oz | 2.6 | 0 |  |  |  |  | P7 | 0 |  |  |  | P7 |  |  |  |  |  |  |
|  | Prepreg |  | 2.7 | 0 |  | 3.5 | 0 |  |  |  |  |  |  |  |  |  |  |  |  |  |
| Bottom | Signal | 0.5 oz+plating | 1.9 | 0 |  |  |  |  | S8 | 4 |  |  |  | S8 | 4 | 9 |  |  |  |  |
|  | Mask |  | 0.5 | 0 |  | 3.8 | 0 |  |  |  |  |  |  |  |  |  |  |  |  |  |
| Thickness requirement: 1.6±10% mm |  | mil | 60.2 |  |  |  |  |  |  |  |  |  |  |  |  |  |  |  |  |  |
|  |  | mm | 1.5290830581661166 |  |  |  |  |  |  |  |  |  |  |  |  |  |  |  |  |  |
| Note: | 1. Unit is mil |  |  |  |  |  |  |  |  |  |  |  |  |  |  |  |  |  |  |  |
|  | 2. The total thickness includes trace and solder mask , not G/F  area |  |  |  |  |  |  |  |  |  |  |  |  |  |  |  |  |  |  |  |
|  | 3. Min hole copper thickness is 1.0 mil |  |  |  |  |  |  |  |  |  |  |  |  |  |  |  |  |  |  |  |
|  | 4. Min surface copper thickness 1.5 mil |  |  |  |  |  |  |  |  |  |  |  |  |  |  |  |  |  |  |  |
